(kicad_pcb
	(version 20260206)
	(generator "pcbnew")
	(generator_version "10.0")
	(general
		(thickness 1.21888)
		(legacy_teardrops no)
	)
	(paper "A4")
	(title_block
		(title "timecard-v7 — TimeCard-DC-V7_EXP.PcbDoc")
		(comment 1 "Time Appliance Project (Time Card) / footprints 113-117 of 160")
	)
	(layers
		(0 "F.Cu" signal "TOP")
		(4 "In1.Cu" signal "SGND")
		(6 "In2.Cu" signal "IN1")
		(8 "In3.Cu" signal "IN2")
		(10 "In4.Cu" signal "SGND1")
		(2 "B.Cu" signal "BOTTOM")
		(9 "F.Adhes" user "F.Adhesive")
		(11 "B.Adhes" user "B.Adhesive")
		(13 "F.Paste" user "Top Paste")
		(15 "B.Paste" user "Bottom Paste")
		(5 "F.SilkS" user "Top Overlay")
		(7 "B.SilkS" user "Bottom Overlay")
		(1 "F.Mask" user "Top Solder")
		(3 "B.Mask" user "Bottom Solder")
		(17 "Dwgs.User" user "User.Drawings")
		(19 "Cmts.User" user "User.Comments")
		(21 "Eco1.User" user "User.Eco1")
		(23 "Eco2.User" user "User.Eco2")
		(25 "Edge.Cuts" user)
		(27 "Margin" user)
		(31 "F.CrtYd" user "Top Courtyard")
		(29 "B.CrtYd" user "Bottom Courtyard")
		(35 "F.Fab" user "Top Component Center")
		(33 "B.Fab" user "Bottom Component Center")
	)
	(footprint "Vault:FP-LTST-C191TBKT-MFG"
		(layer "F.Cu")
		(at 71.6261 52.1162 90)
		(property "Reference" "D9"
			(at -6.771395 -0.223079 90)
			(unlocked yes)
			(layer "F.SilkS")
			(effects
				(font
					(size 0.762 0.762)
					(thickness 0.2286)
				)
			)
		)
		(property "Value" "BLUE"
			(at 1.307195 2.479802 90)
			(unlocked yes)
			(layer "F.SilkS")
			(hide yes)
			(effects
				(font
					(size 1.524 1.524)
					(thickness 0.254)
				)
			)
		)
		(sheetname "USER_IO_STATUS")
		(sheetfile "USER_IO_STATUS.kicad_sch")
		(duplicate_pad_numbers_are_jumpers no)
		(fp_line
			(start -0.85 -0.8)
			(end 0.85 -0.8)
			(stroke
				(width 0.2)
				(type solid)
			)
			(layer "F.SilkS")
		)
		(fp_line
			(start -0.85 0.8)
			(end 0.85 0.8)
			(stroke
				(width 0.2)
				(type solid)
			)
			(layer "F.SilkS")
		)
		(fp_circle
			(center -1.75 0)
			(end -1.625 0)
			(stroke
				(width 0.25)
				(type solid)
			)
			(fill no)
			(layer "F.SilkS")
		)
		(fp_line
			(start 1.25 -0.55)
			(end 1.25 0.55)
			(stroke
				(width 0.2)
				(type solid)
			)
			(layer "F.CrtYd")
		)
		(fp_line
			(start -1.25 -0.55)
			(end 1.25 -0.55)
			(stroke
				(width 0.2)
				(type solid)
			)
			(layer "F.CrtYd")
		)
		(fp_line
			(start -1.25 -0.55)
			(end -1.25 0.55)
			(stroke
				(width 0.2)
				(type solid)
			)
			(layer "F.CrtYd")
		)
		(fp_line
			(start -1.25 0.55)
			(end 1.25 0.55)
			(stroke
				(width 0.2)
				(type solid)
			)
			(layer "F.CrtYd")
		)
		(fp_line
			(start 1.25 -0.55)
			(end 1.25 0.55)
			(stroke
				(width 0.2)
				(type solid)
			)
			(layer "F.Fab")
		)
		(fp_line
			(start -1.25 -0.55)
			(end 1.25 -0.55)
			(stroke
				(width 0.2)
				(type solid)
			)
			(layer "F.Fab")
		)
		(fp_line
			(start -1.25 -0.55)
			(end -1.25 0.55)
			(stroke
				(width 0.2)
				(type solid)
			)
			(layer "F.Fab")
		)
		(fp_line
			(start 0 -0.5)
			(end 0 0.5)
			(stroke
				(width 0.1)
				(type solid)
			)
			(layer "F.Fab")
		)
		(fp_line
			(start -0.5 0)
			(end 0.5 0)
			(stroke
				(width 0.1)
				(type solid)
			)
			(layer "F.Fab")
		)
		(fp_line
			(start -1.25 0.55)
			(end 1.25 0.55)
			(stroke
				(width 0.2)
				(type solid)
			)
			(layer "F.Fab")
		)
		(fp_text user "${REFERENCE}"
			(at 0 0.28425 90)
			(unlocked yes)
			(layer "F.Fab")
			(effects
				(font
					(face "Arial")
					(size 0.63 0.63)
					(thickness 0.1)
				)
				(justify left bottom)
			)
		)
		(pad "1" smd rect
			(at -0.75 0 90)
			(size 0.8 0.8)
			(layers "F.Cu" "F.Mask" "F.Paste")
			(net "NetD9_1")
			(solder_mask_margin 0)
			(solder_paste_margin 0)
		)
		(pad "2" smd rect
			(at 0.75 0 90)
			(size 0.8 0.8)
			(layers "F.Cu" "F.Mask" "F.Paste")
			(net "+3.3V")
			(solder_mask_margin 0)
			(solder_paste_margin 0)
		)
	)
	(footprint "Vault:RESC1608X55X25LL10T15"
		(layer "F.Cu")
		(at 130.3761 85.3286)
		(property "Reference" "R10"
			(at -2.0214 0.014531 0)
			(unlocked yes)
			(layer "F.SilkS")
			(effects
				(font
					(size 0.762 0.762)
					(thickness 0.2286)
				)
			)
		)
		(property "Value" "4.7K"
			(at -2.657602 2.60264 270)
			(unlocked yes)
			(layer "F.SilkS")
			(hide yes)
			(effects
				(font
					(size 1.524 1.524)
					(thickness 0.254)
				)
			)
		)
		(sheetname "MAC")
		(sheetfile "MAC.kicad_sch")
		(duplicate_pad_numbers_are_jumpers no)
		(pad "1" smd rect
			(at -0.65 0 90)
			(size 0.8 0.6)
			(layers "F.Cu" "F.Mask" "F.Paste")
			(net "GND")
		)
		(pad "2" smd rect
			(at 0.65 0 90)
			(size 0.8 0.6)
			(layers "F.Cu" "F.Mask" "F.Paste")
			(net "FPGA_MAC_PPS_IN1-")
		)
	)
	(footprint "Vault:RESC1608X55X30NL15T15"
		(layer "F.Cu")
		(at 84.3761 125.8662 -90)
		(property "Reference" "R16"
			(at 2.7714 -0.026931 90)
			(unlocked yes)
			(layer "F.SilkS")
			(effects
				(font
					(size 0.762 0.762)
					(thickness 0.2286)
				)
			)
		)
		(property "Value" "4.7K"
			(at 0.585402 -4.85075 0)
			(unlocked yes)
			(layer "F.SilkS")
			(hide yes)
			(effects
				(font
					(size 1.524 1.524)
					(thickness 0.254)
				)
			)
		)
		(sheetname "USER_IO")
		(sheetfile "USER_IO.kicad_sch")
		(duplicate_pad_numbers_are_jumpers no)
		(pad "1" smd rect
			(at -0.75 0)
			(size 0.95 0.95)
			(layers "F.Cu" "F.Mask" "F.Paste")
			(net "ANT3_IO_OUT")
		)
		(pad "2" smd rect
			(at 0.75 0)
			(size 0.95 0.95)
			(layers "F.Cu" "F.Mask" "F.Paste")
			(net "+3.3V")
		)
	)
	(footprint "Vault:CAPC1608X87X45ML20T05"
		(layer "F.Cu")
		(at 194.1761 83.5786 180)
		(property "Reference" "C30"
			(at 2.8214 -0.026921 0)
			(unlocked yes)
			(layer "F.SilkS")
			(effects
				(font
					(size 0.762 0.762)
					(thickness 0.2286)
				)
			)
		)
		(property "Value" "0.1uF"
			(at 2.09443 2.657602 180)
			(unlocked yes)
			(layer "F.SilkS")
			(hide yes)
			(effects
				(font
					(size 1.524 1.524)
					(thickness 0.254)
				)
			)
		)
		(sheetname "GPS_IMU_SENSORS")
		(sheetfile "GPS_IMU_SENSORS.kicad_sch")
		(duplicate_pad_numbers_are_jumpers no)
		(pad "1" smd rect
			(at -0.7 0 270)
			(size 1.1 1.05)
			(layers "F.Cu" "F.Mask" "F.Paste")
			(net "GND")
		)
		(pad "2" smd rect
			(at 0.7 0 270)
			(size 1.1 1.05)
			(layers "F.Cu" "F.Mask" "F.Paste")
			(net "+3.3V")
		)
	)
	(footprint "Miscellaneous Connectors:HDR2X6_CEN"
		(layer "F.Cu")
		(at 212.7461 51.5762 180)
		(property "Reference" "P3"
			(at 18.324329 -2.146705 90)
			(unlocked yes)
			(layer "F.SilkS")
			(effects
				(font
					(size 0.762 0.762)
					(thickness 0.2286)
				)
			)
		)
		(property "Value" "EXT GPIO"
			(at -4.308602 2.32225 90)
			(unlocked yes)
			(layer "F.SilkS")
			(hide yes)
			(effects
				(font
					(size 1.524 1.524)
					(thickness 0.254)
				)
			)
		)
		(sheetname "GPS_IMU_SENSORS")
		(sheetfile "GPS_IMU_SENSORS.kicad_sch")
		(duplicate_pad_numbers_are_jumpers no)
		(fp_line
			(start 13.97 1.27)
			(end -1.27 1.27)
			(stroke
				(width 0.2)
				(type solid)
			)
			(layer "F.SilkS")
		)
		(fp_line
			(start 13.97 -3.81)
			(end 13.97 1.27)
			(stroke
				(width 0.2)
				(type solid)
			)
			(layer "F.SilkS")
		)
		(fp_line
			(start 13.97 -3.81)
			(end -1.27 -3.81)
			(stroke
				(width 0.2)
				(type solid)
			)
			(layer "F.SilkS")
		)
		(fp_line
			(start -1.27 -3.81)
			(end -1.27 1.27)
			(stroke
				(width 0.2)
				(type solid)
			)
			(layer "F.SilkS")
		)
		(fp_text user "6"
			(at 14.732 0.663575 180)
			(unlocked yes)
			(layer "F.SilkS")
			(effects
				(font
					(size 1.27 1.27)
					(thickness 0.2032)
				)
				(justify left bottom)
			)
		)
		(fp_text user "12"
			(at 14.732 -1.876425 180)
			(unlocked yes)
			(layer "F.SilkS")
			(effects
				(font
					(size 1.27 1.27)
					(thickness 0.2032)
				)
				(justify left bottom)
			)
		)
		(fp_text user "1"
			(at -2.54 0.663575 180)
			(unlocked yes)
			(layer "F.SilkS")
			(effects
				(font
					(size 1.27 1.27)
					(thickness 0.2032)
				)
				(justify left bottom)
			)
		)
		(fp_text user "7"
			(at -2.54 -1.876425 180)
			(unlocked yes)
			(layer "F.SilkS")
			(effects
				(font
					(size 1.27 1.27)
					(thickness 0.2032)
				)
				(justify left bottom)
			)
		)
		(pad "1" thru_hole rect
			(at 0 0 180)
			(size 1.5 1.5)
			(drill 0.9)
			(layers "*.Cu" "*.Mask")
			(remove_unused_layers no)
			(net "EXT_GPIO_1")
		)
		(pad "2" thru_hole circle
			(at 2.54 0 180)
			(size 1.5 1.5)
			(drill 0.9)
			(layers "*.Cu" "*.Mask")
			(remove_unused_layers no)
			(net "EXT_GPIO_2")
			(thermal_bridge_angle 90)
		)
		(pad "3" thru_hole circle
			(at 5.08 0 180)
			(size 1.5 1.5)
			(drill 0.9)
			(layers "*.Cu" "*.Mask")
			(remove_unused_layers no)
			(net "EXT_GPIO_3")
			(thermal_bridge_angle 90)
		)
		(pad "4" thru_hole circle
			(at 7.62 0 180)
			(size 1.5 1.5)
			(drill 0.9)
			(layers "*.Cu" "*.Mask")
			(remove_unused_layers no)
			(net "EXT_GPIO_4")
			(thermal_bridge_angle 90)
		)
		(pad "5" thru_hole circle
			(at 10.16 0 180)
			(size 1.5 1.5)
			(drill 0.9)
			(layers "*.Cu" "*.Mask")
			(remove_unused_layers no)
			(net "GND")
			(thermal_bridge_angle 90)
		)
		(pad "6" thru_hole circle
			(at 12.7 0 180)
			(size 1.5 1.5)
			(drill 0.9)
			(layers "*.Cu" "*.Mask")
			(remove_unused_layers no)
			(net "+3.3V")
			(thermal_bridge_angle 90)
		)
		(pad "7" thru_hole circle
			(at 0 -2.54 180)
			(size 1.5 1.5)
			(drill 0.9)
			(layers "*.Cu" "*.Mask")
			(remove_unused_layers no)
			(net "EXT_GPIO_7")
			(thermal_bridge_angle 90)
		)
		(pad "8" thru_hole circle
			(at 2.54 -2.54 180)
			(size 1.5 1.5)
			(drill 0.9)
			(layers "*.Cu" "*.Mask")
			(remove_unused_layers no)
			(net "EXT_GPIO_8")
			(thermal_bridge_angle 90)
		)
		(pad "9" thru_hole circle
			(at 5.08 -2.54 180)
			(size 1.5 1.5)
			(drill 0.9)
			(layers "*.Cu" "*.Mask")
			(remove_unused_layers no)
			(net "EXT_GPIO_9")
			(thermal_bridge_angle 90)
		)
		(pad "10" thru_hole circle
			(at 7.62 -2.54 180)
			(size 1.5 1.5)
			(drill 0.9)
			(layers "*.Cu" "*.Mask")
			(remove_unused_layers no)
			(net "EXT_GPIO_10")
			(thermal_bridge_angle 90)
		)
		(pad "11" thru_hole circle
			(at 10.16 -2.54 180)
			(size 1.5 1.5)
			(drill 0.9)
			(layers "*.Cu" "*.Mask")
			(remove_unused_layers no)
			(net "GND")
			(thermal_bridge_angle 90)
		)
		(pad "12" thru_hole circle
			(at 12.7 -2.54 180)
			(size 1.5 1.5)
			(drill 0.9)
			(layers "*.Cu" "*.Mask")
			(remove_unused_layers no)
			(net "+3.3V")
			(thermal_bridge_angle 90)
		)
	)
)
